FILE_TYPE = CONNECTIVITY;
{Allegro Design Entry HDL 16.6-p007 (v16-6-112F) 10/10/2012}
"PAGE_NUMBER" = 156;
0"NC";
1"P3V3_STBY\g";
2"P3V3_STBY\g";
3"P3V3_STBY\g";
4"GND\g";
5"P3V3_STBY\g";
6"P3V3_STBY\g";
7"GND\g";
8"GND\g";
9"P3V3_STBY\g";
10"GND\g";
11"GND\g";
12"GND\g";
13"P3V3_STBY\g";
14"P3V3_STBY\g";
15"GND\g";
16"GND\g";
17"P3V3_STBY\g";
18"SMB_HOST_STBY_LVC3_SDA";
19"SMB_HOST_STBY_LVC3_SCL";
20"FM_CPU0_SM_WP";
21"SMB_SMLINK0_STBY_LVC3_SCL";
22"SMB_SMLINK0_STBY_LVC3_SDA";
23"FM_MEM_THERM_EVENT_LVT3_N";
24"IRQ_BMC_PCH_NMI_STBY_N";
25"SMB_PIROM_CPU1_SDA";
26"FM_ADR_SMI_GPIO_N";
27"IRQ_BMC_PCH_NMI_STBY_R_N";
28"FM_CPU1_SM_WP";
29"FM_BMC_PWRBTN_OUT_N";
30"PD_PIROM_CPU0_ADDR2";
31"PD_PIROM_CPU0_ADDR1";
32"PD_PIROM_CPU0_ADDR0";
33"FM_CPU_BMC_INIT";
34"FM_PCH_PWRBTN_OUT_N";
35"RST_PCH_SYSRST_BTN_OUT_N";
36"H_CPU0_BMCINIT";
37"H_CPU1_BMCINIT";
38"PU_PIROM_CPU1_ADDR0";
39"PD_PIROM_CPU1_ADDR1";
40"PD_PIROM_CPU1_ADDR2";
41"RST_BMC_SYSRST_BTN_OUT_N";
42"RST_BMC_SYSRST_BTN_OUT_B_R_N";
43"FM_PCH_PWRBTN_R_N";
44"FM_PCH_PWRBTN_N";
45"RST_BMC_SYSRST_BTN_OUT_B_N";
46"SMB_PIROM_CPU0_SDA";
47"SMB_LAN_STBY_LVC3_SCL";
48"SMB_PIROM_CPU0_SCL";
49"SMB_PIROM_CPU1_SCL";
50"SMB_LAN_STBY_LVC3_SDA";
%"TTL2G07"
"1","(-3000,4150)","0","mstr_ttl","I201";
;
CDS_SEC"1"
CDS_LIB"mstr_ttl"
PACK_TYPE"SOT23LF"
ROOM"BMC_MISC"
CDS_LOCATION"U8F3"
SEC"1"
SEC_TYPE"SOT23LF"
BOM_COST"SM_CONTROLLER"
VALUE"74LVC2G07"
LOCATION"U8F3"
MATERIAL"IC"
POWER_GROUP"VCC=P3V3_STBY;GND=GND"
PART_NUMBER"D22707-001";
"1Y"
$PN"6"42;
"2Y"
$PN"4"43;
"1A"
$PN"1"41;
"2A"
$PN"3"29;
%"RES"
"2","(-4150,4450)","0","mstr_discrete","I206";
;
CDS_SEC"1"
ROOM"BMC_MISC"
SEC"1"
SEC_TYPE"0402"
BOM_COST"SM_CONTROLLER"
CDS_LIB"mstr_discrete"
CDS_LOCATION"R2T34"
LOCATION"R2T34"
PART_NUMBER"G21796-072"
VALUE"4.75K"
TOLERANCE"1%"
PACK_TYPE"0402"
MATERIAL"CHIP"
WATTAGE"1/16W";
"A"
$PN"1"1;
"B"
$PN"2"29;
%"RES"
"2","(-3825,4450)","0","mstr_discrete","I207";
;
CDS_SEC"1"
ROOM"BMC_MISC"
SEC"1"
BOM_COST"SM_CONTROLLER"
SEC_TYPE"0402"
CDS_LIB"mstr_discrete"
CDS_LOCATION"R2T35"
PART_NUMBER"G21796-072"
WATTAGE"1/16W"
MATERIAL"CHIP"
LOCATION"R2T35"
VALUE"4.75K"
TOLERANCE"1%"
PACK_TYPE"0402";
"A"
$PN"1"1;
"B"
$PN"2"41;
%"P3V3_STBY"
"1","(-4150,4850)","0","mstr_symbols","I208";
;
HDL_POWER"P3V3_STBY"
BODY_TYPE"PLUMBING"
SIZE"1B"
CDS_LIB"mstr_symbols"
VOLTAGE"3.3V";
"G\NAC"1;
%"P3V3_STBY"
"1","(-2400,4850)","0","mstr_symbols","I209";
;
HDL_POWER"P3V3_STBY"
BODY_TYPE"PLUMBING"
SIZE"1B"
CDS_LIB"mstr_symbols"
VOLTAGE"3.3V";
"G\NAC"2;
%"RES"
"2","(-2275,4425)","0","mstr_discrete","I210";
;
CDS_SEC"1"
BOM_COST"SM_CONTROLLER"
SEC_TYPE"0402"
SEC"1"
ROOM"BMC_MISC"
CDS_LOCATION"R2T22"
CDS_LIB"mstr_discrete"
PART_NUMBER"G21796-016"
WATTAGE"1/16W"
LOCATION"R2T22"
TOLERANCE"1%"
VALUE"10.0K"
MATERIAL"CHIP"
PACK_TYPE"0402";
"A"
$PN"1"2;
"B"
$PN"2"42;
%"RES"
"2","(-2550,4450)","0","mstr_discrete","I211";
;
CDS_SEC"1"
BOM_COST"SM_CONTROLLER"
SEC_TYPE"0402"
SEC"1"
ROOM"BMC_MISC"
CDS_LIB"mstr_discrete"
CDS_LOCATION"R8F26"
PART_NUMBER"G21796-016"
WATTAGE"1/16W"
MATERIAL"CHIP"
TOLERANCE"1%"
VALUE"10.0K"
LOCATION"R8F26"
PACK_TYPE"0402";
"A"
$PN"1"2;
"B"
$PN"2"43;
%"RES"
"1","(-6575,2775)","0","mstr_discrete","I214";
;
CDS_SEC"1"
ROOM"BMC_MISC"
CDS_LOCATION"R8E24"
SEC"1"
BOM_COST"SM_CONTROLLER"
SEC_TYPE"0402"
CDS_LIB"mstr_discrete"
PACK_TYPE"0402"
LOCATION"R8E24"
TOLERANCE"1%"
MATERIAL"CHIP"
PART_NUMBER"G21796-074"
VALUE"33.2"
WATTAGE"1/16W";
"B"
$PN"2"27;
"A"
$PN"1"24;
%"RES"
"2","(-6825,3025)","0","mstr_discrete","I215";
;
CDS_SEC"1"
ROOM"BMC_MISC"
CDS_LOCATION"R8E22"
SEC"1"
BOM_COST"SM_CONTROLLER"
SEC_TYPE"0402"
CDS_LIB"mstr_discrete"
LOCATION"R8E22"
VALUE"4.75K"
TOLERANCE"1%"
PART_NUMBER"G21796-072"
WATTAGE"1/16W"
PACK_TYPE"0402"
MATERIAL"CHIP";
"A"
$PN"1"3;
"B"
$PN"2"24;
%"P3V3_STBY"
"1","(-6825,3275)","0","mstr_symbols","I216";
;
HDL_POWER"P3V3_STBY"
BODY_TYPE"PLUMBING"
SIZE"1B"
VOLTAGE"3.3V"
CDS_LIB"mstr_symbols";
"G\NAC"3;
%"GND"
"1","(-7275,4225)","0","mstr_symbols","I257";
;
HDL_POWER"GND"
BODY_TYPE"PLUMBING"
CDS_LIB"mstr_symbols"
SIZE"1B"
VOLTAGE"0.0V";
"A\NAC"4;
%"RES"
"2","(-3750,3550)","0","mstr_discrete","I265";
;
CDS_SEC"1"
ROOM"BMC_MISC"
CDS_LOCATION"R2U2"
SEC"1"
SEC_TYPE"0402"
BOM_COST"SM_CONTROLLER"
CDS_LIB"mstr_discrete"
PART_NUMBER"G21796-072"
VALUE"4.75K"
WATTAGE"1/16W"
LOCATION"R2U2"
TOLERANCE"1%"
MATERIAL"CHIP"
PACK_TYPE"0402";
"A"
$PN"1"5;
"B"
$PN"2"35;
%"P3V3_STBY"
"1","(-4075,3950)","0","mstr_symbols","I266";
;
HDL_POWER"P3V3_STBY"
BODY_TYPE"PLUMBING"
CDS_LIB"mstr_symbols"
SIZE"1B"
VOLTAGE"3.3V";
"G\NAC"5;
%"RES"
"2","(-4075,3550)","0","mstr_discrete","I267";
;
CDS_SEC"1"
ROOM"BMC_MISC"
SEC"1"
BOM_COST"SM_CONTROLLER"
SEC_TYPE"0402"
CDS_LOCATION"R8G2"
CDS_LIB"mstr_discrete"
LOCATION"R8G2"
VALUE"4.75K"
TOLERANCE"1%"
PART_NUMBER"G21796-072"
WATTAGE"1/16W"
MATERIAL"CHIP"
PACK_TYPE"0402";
"A"
$PN"1"5;
"B"
$PN"2"34;
%"TTL2G07"
"1","(-2925,3250)","0","mstr_ttl","I269";
;
CDS_SEC"1"
CDS_LIB"mstr_ttl"
BOM_COST"SM_CONTROLLER"
SEC_TYPE"SOT23LF"
SEC"1"
CDS_LOCATION"U8G1"
ROOM"BMC_MISC"
PACK_TYPE"SOT23LF"
VALUE"74LVC2G07"
POWER_GROUP"VCC=P3V3_STBY;GND=GND"
LOCATION"U8G1"
PART_NUMBER"D22707-001"
MATERIAL"IC";
"1Y"
$PN"6"42;
"2Y"
$PN"4"43;
"1A"
$PN"1"35;
"2A"
$PN"3"34;
%"P3V3_STBY"
"1","(-450,3850)","0","mstr_symbols","I272";
;
HDL_POWER"P3V3_STBY"
BODY_TYPE"PLUMBING"
SIZE"1B"
CDS_LIB"mstr_symbols"
VOLTAGE"3.3V";
"G\NAC"6;
%"CAP_A"
"1","(-450,3550)","0","dev_discrete","I273";
;
SEC_TYPE"0402V"
BOM_COST"SM_CONTROLLER"
ROOM"BMC_MISC"
SEC"1"
CDS_SEC"1"
CDS_LOCATION"C2T35"
CDS_LIB"dev_discrete"
VALUE"0.1UF"
LOCATION"C2T35"
PART_NUMBER"A36096-030"
PACK_TYPE"0402V"
TOLERANCE"10%"
VOLTAGE"16V"
MATERIAL"X7R";
"B"
$PN"2"7;
"A"
$PN"1"6;
%"GND"
"1","(-450,3250)","0","mstr_symbols","I274";
;
HDL_POWER"GND"
BODY_TYPE"PLUMBING"
VOLTAGE"0.0V"
SIZE"1B"
CDS_LIB"mstr_symbols";
"A\NAC"7;
%"CAP_A"
"1","(-450,4450)","0","dev_discrete","I275";
;
SEC_TYPE"0402V"
BOM_COST"SM_CONTROLLER"
ROOM"BMC_MISC"
SEC"1"
CDS_SEC"1"
CDS_LIB"dev_discrete"
CDS_LOCATION"C8F16"
LOCATION"C8F16"
PART_NUMBER"A36096-030"
VALUE"0.1UF"
PACK_TYPE"0402V"
TOLERANCE"10%"
VOLTAGE"16V"
MATERIAL"X7R";
"B"
$PN"2"8;
"A"
$PN"1"9;
%"GND"
"1","(-450,4150)","0","mstr_symbols","I276";
;
HDL_POWER"GND"
BODY_TYPE"PLUMBING"
SIZE"1B"
CDS_LIB"mstr_symbols"
VOLTAGE"0.0V";
"A\NAC"8;
%"P3V3_STBY"
"1","(-450,4750)","0","mstr_symbols","I277";
;
HDL_POWER"P3V3_STBY"
BODY_TYPE"PLUMBING"
VOLTAGE"3.3V"
SIZE"1B"
CDS_LIB"mstr_symbols";
"G\NAC"9;
%"RES"
"1","(-6600,2350)","0","mstr_discrete","I279";
;
CDS_SEC"1"
BOM_COST"SM_CONTROLLER"
ROOM"BMC_MISC"
SEC"1"
SEC_TYPE"0402"
CDS_LOCATION"R8E11"
CDS_LIB"mstr_discrete"
PACK_TYPE"0402"
PART_NUMBER"G21497-005"
LOCATION"R8E11"
MATERIAL"EMPTY"
TOLERANCE"5%"
VALUE"0.0"
WATTAGE"1/16W";
"B"
$PN"2"26;
"A"
$PN"1"23;
%"CONN3_C95678002"
"1","(-7575,3700)","0","mstr_conn","I281";
;
CDS_SEC"1"
BOM_COST"DEBUG"
PACK_TYPE"PIP"
ROOM"DEBUG"
CDS_LOCATION"J9B2"
SEC"1"
SEC_TYPE"PIP"
CDS_LIB"mstr_conn"
LOCATION"J9B2"
MATERIAL"CONN"
PART_NUMBER"C95678-002";
"IO1 \B"
$PN"1"22;
"IO2 \B"
$PN"2"10;
"IO3 \B"
$PN"3"21;
%"GND"
"1","(-7275,3475)","0","mstr_symbols","I282";
;
HDL_POWER"GND"
BODY_TYPE"PLUMBING"
VOLTAGE"0.0V"
SIZE"1B"
CDS_LIB"mstr_symbols";
"A\NAC"10;
%"CONN3_C95678002"
"1","(-7600,4475)","0","mstr_conn","I285";
;
CDS_SEC"1"
PACK_TYPE"PIP"
ROOM"DEBUG"
CDS_LOCATION"J8C1"
SEC"1"
BOM_COST"DEBUG"
SEC_TYPE"PIP"
CDS_LIB"mstr_conn"
PART_NUMBER"C95678-002"
LOCATION"J8C1"
MATERIAL"CONN";
"IO1 \B"
$PN"1"18;
"IO2 \B"
$PN"2"4;
"IO3 \B"
$PN"3"19;
%"RES"
"1","(-1700,4150)","0","mstr_discrete","I288";
;
CDS_SEC"1"
ROOM"BMC_MISC"
BOM_COST"SM_CONTROLLER"
SEC_TYPE"0402"
SEC"1"
CDS_LOCATION"R2T18"
CDS_LIB"mstr_discrete"
WATTAGE"1/16W"
PACK_TYPE"0402"
MATERIAL"CHIP"
PART_NUMBER"G21796-047"
LOCATION"R2T18"
TOLERANCE"1%"
VALUE"49.9";
"B"
$PN"2"45;
"A"
$PN"1"42;
%"RES"
"1","(-1700,4100)","6","mstr_discrete","I289";
;
CDS_SEC"1"
WATTAGE"1/16W"
ROOM"BMC_MISC"
BOM_COST"SM_CONTROLLER"
CDS_LOCATION"R2T28"
SEC"1"
SEC_TYPE"0402"
CDS_LIB"mstr_discrete"
PACK_TYPE"0402"
MATERIAL"CHIP"
PART_NUMBER"G21796-074"
LOCATION"R2T28"
VALUE"33.2"
TOLERANCE"1%";
"B"
$PN"2"44;
"A"
$PN"1"43;
%"RES"
"1","(-2900,1825)","0","mstr_discrete","I299";
;
CDS_SEC"1"
CDS_LOCATION"R6D16"
BOM_COST"SM_CONTROLLER"
SEC"1"
SEC_TYPE"0402"
ROOM"BMC_MISC"
CDS_LIB"mstr_discrete"
TOLERANCE"5%"
WATTAGE"1/16W"
PART_NUMBER"G21497-005"
MATERIAL"EMPTY"
PACK_TYPE"0402"
LOCATION"R6D16"
VALUE"0.0";
"B"
$PN"2"36;
"A"
$PN"1"33;
%"RES"
"1","(-2900,1550)","0","mstr_discrete","I300";
;
CDS_SEC"1"
CDS_LOCATION"R3D31"
BOM_COST"SM_CONTROLLER"
ROOM"BMC_MISC"
SEC_TYPE"0402"
CDS_LIB"mstr_discrete"
SEC"1"
TOLERANCE"5%"
WATTAGE"1/16W"
PART_NUMBER"G21497-005"
MATERIAL"EMPTY"
LOCATION"R3D31"
PACK_TYPE"0402"
VALUE"0.0";
"B"
$PN"2"37;
"A"
$PN"1"33;
%"RES"
"1","(-4000,975)","0","mstr_discrete","I302";
;
CDS_SEC"1"
CDS_LOCATION"R6N14"
SEC_TYPE"0402"
SEC"1"
ROOM"CPU0"
PACK_TYPE"0402"
CDS_LIB"mstr_discrete"
MATERIAL"CHIP"
LOCATION"R6N14"
PART_NUMBER"G21796-026"
WATTAGE"1/16W"
TOLERANCE"1%"
VALUE"1.00K";
"B"
$PN"2"32;
"A"
$PN"1"11;
%"RES"
"1","(-4000,775)","0","mstr_discrete","I303";
;
CDS_SEC"1"
CDS_LOCATION"R6N13"
PACK_TYPE"0402"
SEC_TYPE"0402"
SEC"1"
ROOM"CPU0"
CDS_LIB"mstr_discrete"
MATERIAL"CHIP"
WATTAGE"1/16W"
PART_NUMBER"G21796-026"
LOCATION"R6N13"
TOLERANCE"1%"
VALUE"1.00K";
"B"
$PN"2"31;
"A"
$PN"1"11;
%"RES"
"1","(-4000,575)","0","mstr_discrete","I304";
;
CDS_SEC"1"
CDS_LOCATION"R6N15"
SEC"1"
SEC_TYPE"0402"
CDS_LIB"mstr_discrete"
ROOM"CPU0"
PACK_TYPE"0402"
MATERIAL"CHIP"
WATTAGE"1/16W"
PART_NUMBER"G21796-026"
LOCATION"R6N15"
TOLERANCE"1%"
VALUE"1.00K";
"B"
$PN"2"30;
"A"
$PN"1"11;
%"GND"
"1","(-4275,425)","0","mstr_symbols","I306";
;
HDL_POWER"GND"
BODY_TYPE"PLUMBING"
VOLTAGE"0.0V"
SIZE"1B"
CDS_LIB"mstr_symbols";
"A\NAC"11;
%"GND"
"1","(-2175,425)","0","mstr_symbols","I311";
;
HDL_POWER"GND"
BODY_TYPE"PLUMBING"
VOLTAGE"0.0V"
SIZE"1B"
CDS_LIB"mstr_symbols";
"A\NAC"12;
%"RES"
"1","(-1900,575)","0","mstr_discrete","I312";
;
CDS_SEC"1"
CDS_LOCATION"R1C32"
SEC_TYPE"0402"
SEC"1"
CDS_LIB"mstr_discrete"
ROOM"CPU1"
PACK_TYPE"0402"
MATERIAL"CHIP"
PART_NUMBER"G21796-026"
WATTAGE"1/16W"
LOCATION"R1C32"
TOLERANCE"1%"
VALUE"1.00K";
"B"
$PN"2"40;
"A"
$PN"1"12;
%"RES"
"1","(-1900,775)","0","mstr_discrete","I313";
;
CDS_SEC"1"
CDS_LOCATION"R1C33"
PACK_TYPE"0402"
CDS_LIB"mstr_discrete"
SEC_TYPE"0402"
SEC"1"
ROOM"CPU1"
MATERIAL"CHIP"
PART_NUMBER"G21796-026"
WATTAGE"1/16W"
TOLERANCE"1%"
LOCATION"R1C33"
VALUE"1.00K";
"B"
$PN"2"39;
"A"
$PN"1"12;
%"P3V3_STBY"
"1","(-2175,1100)","0","mstr_symbols","I318";
;
HDL_POWER"P3V3_STBY"
BODY_TYPE"PLUMBING"
VOLTAGE"3.3V"
CDS_LIB"mstr_symbols"
SIZE"1B";
"G\NAC"13;
%"RES"
"1","(-1900,975)","0","mstr_discrete","I320";
;
CDS_SEC"1"
CDS_LOCATION"R1C34"
ROOM"CPU1"
SEC"1"
SEC_TYPE"0402"
PACK_TYPE"0402"
CDS_LIB"mstr_discrete"
MATERIAL"CHIP"
LOCATION"R1C34"
PART_NUMBER"G21796-016"
WATTAGE"1/16W"
TOLERANCE"1%"
VALUE"10.0K";
"B"
$PN"2"38;
"A"
$PN"1"13;
%"RES"
"1","(-6425,850)","0","mstr_discrete","I321";
;
CDS_SEC"1"
CDS_LOCATION"R9M21"
SEC"1"
SEC_TYPE"0402"
ROOM"CPU1"
CDS_LIB"mstr_discrete"
TOLERANCE"5%"
MATERIAL"CHIP"
WATTAGE"1/16W"
PART_NUMBER"G21497-005"
PACK_TYPE"0402"
LOCATION"R9M21"
VALUE"0.0";
"B"
$PN"2"25;
"A"
$PN"1"50;
%"RES"
"1","(-6425,700)","0","mstr_discrete","I322";
;
CDS_SEC"1"
CDS_LOCATION"R4A8"
ROOM"CPU0"
SEC"1"
SEC_TYPE"0402"
CDS_LIB"mstr_discrete"
TOLERANCE"5%"
MATERIAL"CHIP"
WATTAGE"1/16W"
VALUE"0.0"
PART_NUMBER"G21497-005"
PACK_TYPE"0402"
LOCATION"R4A8";
"B"
$PN"2"46;
"A"
$PN"1"50;
%"RES"
"1","(-6425,550)","0","mstr_discrete","I323";
;
CDS_SEC"1"
CDS_LOCATION"R9M20"
ROOM"CPU1"
SEC"1"
SEC_TYPE"0402"
CDS_LIB"mstr_discrete"
TOLERANCE"5%"
MATERIAL"CHIP"
WATTAGE"1/16W"
PACK_TYPE"0402"
LOCATION"R9M20"
PART_NUMBER"G21497-005"
VALUE"0.0";
"B"
$PN"2"49;
"A"
$PN"1"47;
%"RES"
"1","(-6425,400)","0","mstr_discrete","I324";
;
CDS_SEC"1"
CDS_LOCATION"R4A9"
ROOM"CPU0"
SEC_TYPE"0402"
SEC"1"
CDS_LIB"mstr_discrete"
TOLERANCE"5%"
MATERIAL"CHIP"
WATTAGE"1/16W"
PART_NUMBER"G21497-005"
PACK_TYPE"0402"
VALUE"0.0"
LOCATION"R4A9";
"B"
$PN"2"48;
"A"
$PN"1"47;
%"RES"
"2","(-7650,1700)","0","mstr_discrete","I331";
;
CDS_SEC"1"
CDS_LOCATION"R3P54"
SEC_TYPE"0402"
SEC"1"
ROOM"CPU0"
CDS_LIB"mstr_discrete"
MATERIAL"EMPTY"
PART_NUMBER"G21796-027"
VALUE"3.32K"
WATTAGE"1/16W"
LOCATION"R3P54"
TOLERANCE"1%"
PACK_TYPE"0402";
"A"
$PN"1"14;
"B"
$PN"2"20;
%"P3V3_STBY"
"1","(-7650,1950)","0","mstr_symbols","I332";
;
HDL_POWER"P3V3_STBY"
BODY_TYPE"PLUMBING"
SIZE"1B"
CDS_LIB"mstr_symbols"
VOLTAGE"3.3V";
"G\NAC"14;
%"RES"
"2","(-7650,1325)","0","mstr_discrete","I333";
;
CDS_SEC"1"
CDS_LOCATION"R3P56"
SEC_TYPE"0402"
SEC"1"
ROOM"CPU0"
CDS_LIB"mstr_discrete"
PART_NUMBER"G21796-026"
WATTAGE"1/16W"
TOLERANCE"1%"
VALUE"1.00K"
LOCATION"R3P56"
MATERIAL"CHIP"
PACK_TYPE"0402";
"A"
$PN"1"20;
"B"
$PN"2"15;
%"GND"
"1","(-7650,1075)","0","mstr_symbols","I334";
;
HDL_POWER"GND"
BODY_TYPE"PLUMBING"
SIZE"1B"
CDS_LIB"mstr_symbols"
VOLTAGE"0.0V";
"A\NAC"15;
%"RES"
"2","(-6025,1725)","0","mstr_discrete","I336";
;
CDS_SEC"1"
CDS_LOCATION"R1C35"
ROOM"CPU1"
SEC"1"
SEC_TYPE"0402"
CDS_LIB"mstr_discrete"
TOLERANCE"1%"
WATTAGE"1/16W"
MATERIAL"EMPTY"
LOCATION"R1C35"
PART_NUMBER"G21796-027"
VALUE"3.32K"
PACK_TYPE"0402";
"A"
$PN"1"17;
"B"
$PN"2"28;
%"RES"
"2","(-6025,1350)","0","mstr_discrete","I337";
;
CDS_SEC"1"
CDS_LOCATION"R1C36"
ROOM"CPU1"
SEC"1"
SEC_TYPE"0402"
CDS_LIB"mstr_discrete"
TOLERANCE"1%"
VALUE"1.00K"
WATTAGE"1/16W"
MATERIAL"CHIP"
PART_NUMBER"G21796-026"
PACK_TYPE"0402"
LOCATION"R1C36";
"A"
$PN"1"28;
"B"
$PN"2"16;
%"GND"
"1","(-6025,1100)","0","mstr_symbols","I338";
;
HDL_POWER"GND"
BODY_TYPE"PLUMBING"
SIZE"1B"
CDS_LIB"mstr_symbols"
VOLTAGE"0.0V";
"A\NAC"16;
%"P3V3_STBY"
"1","(-6025,1975)","0","mstr_symbols","I339";
;
HDL_POWER"P3V3_STBY"
BODY_TYPE"PLUMBING"
SIZE"1B"
VOLTAGE"3.3V"
CDS_LIB"mstr_symbols";
"G\NAC"17;
END.
